(kicad_pcb
	(version 20260206)
	(generator "pcbnew")
	(generator_version "10.0")
	(general
		(thickness 1.6)
		(legacy_teardrops no)
	)
	(paper "A4")
	(title_block
		(title "01162023_DA0F0TEBIF0_F0T_Expander_BD_F_brd_V02_OCP.brd")
		(comment 1 "Grand Teton / footprint 4606 of 9728 (U113), pads 1-101 of 101")
	)
	(layers
		(0 "F.Cu" signal "TOP")
		(4 "In1.Cu" signal "GND")
		(6 "In2.Cu" signal "VCC")
		(8 "In3.Cu" signal "VCC1")
		(10 "In4.Cu" signal "GND1")
		(12 "In5.Cu" signal "IN1")
		(14 "In6.Cu" signal "GND2")
		(16 "In7.Cu" signal "IN2")
		(18 "In8.Cu" signal "GND3")
		(20 "In9.Cu" signal "IN3")
		(22 "In10.Cu" signal "GND4")
		(24 "In11.Cu" signal "IN4")
		(26 "In12.Cu" signal "GND5")
		(28 "In13.Cu" signal "IN5")
		(30 "In14.Cu" signal "GND6")
		(32 "In15.Cu" signal "IN6")
		(34 "In16.Cu" signal "GND7")
		(2 "B.Cu" signal "BOTTOM")
		(9 "F.Adhes" user "F.Adhesive")
		(11 "B.Adhes" user "B.Adhesive")
		(13 "F.Paste" user "Package Geometry/Pastemask Top")
		(15 "B.Paste" user "Package Geometry/Pastemask Bottom")
		(5 "F.SilkS" user "Ref Des/Silkscreen Top")
		(7 "B.SilkS" user "Ref Des/Silkscreen Bottom")
		(1 "F.Mask" user "Board Geometry/Soldermask Top")
		(3 "B.Mask" user "Board Geometry/Soldermask Bottom")
		(17 "Dwgs.User" user "User.Drawings")
		(19 "Cmts.User" user "User.Comments")
		(21 "Eco1.User" user "User.Eco1")
		(23 "Eco2.User" user "User.Eco2")
		(25 "Edge.Cuts" user "Board Geometry/Outline")
		(27 "Margin" user)
		(31 "F.CrtYd" user "Package Geometry/Place Bound Top")
		(29 "B.CrtYd" user "Package Geometry/Place Bound Bottom")
		(35 "F.Fab" user "Ref Des/Assembly Top")
		(33 "B.Fab" user "Ref Des/Assembly Bottom")
	)
	(footprint ""
		(layer "F.Cu")
		(at 259.6769 -84.30641)
		(property "Reference" "U113"
			(at 2.6035 -4.74472 0)
			(unlocked yes)
			(layer "F.SilkS")
			(effects
				(font
					(size 0.7874 0.5842)
					(thickness 0.1524)
				)
				(justify left)
			)
		)
		(property "Value" ""
			(at 0 0 0)
			(layer "F.Fab")
			(effects
				(font
					(size 1.27 1.27)
				)
			)
		)
		(duplicate_pad_numbers_are_jumpers no)
		(pad "A1" smd rect
			(at -3.875024 -3.24993 90)
			(size 0.1778 0.5588)
			(layers "F.Cu" "F.Mask" "F.Paste")
			(net "FM_CK440Q_DEV_25M_EN")
		)
		(pad "A2" smd rect
			(at -3.875024 -2.750058 90)
			(size 0.1778 0.5588)
			(layers "F.Cu" "F.Mask" "F.Paste")
			(net "Net_4267")
		)
		(pad "A3" smd rect
			(at -3.875024 -2.249932 90)
			(size 0.1778 0.5588)
			(layers "F.Cu" "F.Mask" "F.Paste")
			(net "Net_4266")
		)
		(pad "A4" smd rect
			(at -3.875024 -1.75006 90)
			(size 0.1778 0.5588)
			(layers "F.Cu" "F.Mask" "F.Paste")
			(net "Net_4265")
		)
		(pad "A5" smd rect
			(at -3.875024 -1.249934 90)
			(size 0.1778 0.5588)
			(layers "F.Cu" "F.Mask" "F.Paste")
			(net "Net_4264")
		)
		(pad "A6" smd rect
			(at -3.875024 -0.750062 90)
			(size 0.1778 0.5588)
			(layers "F.Cu" "F.Mask" "F.Paste")
			(net "TP_CLK_CK440_PFT_OUT_DP")
		)
		(pad "A7" smd rect
			(at -3.875024 -0.249936 90)
			(size 0.1778 0.5588)
			(layers "F.Cu" "F.Mask" "F.Paste")
			(net "TP_CLK_CK440_PFT_OUT_DN")
		)
		(pad "A8" smd rect
			(at -3.875024 0.249936 90)
			(size 0.1778 0.5588)
			(layers "F.Cu" "F.Mask" "F.Paste")
			(net "TP_CLK_PFT_IN_DP")
		)
		(pad "A9" smd rect
			(at -3.875024 0.750062 90)
			(size 0.1778 0.5588)
			(layers "F.Cu" "F.Mask" "F.Paste")
			(net "TP_CLK_PFT_IN_DN")
		)
		(pad "A10" smd rect
			(at -3.875024 1.249934 90)
			(size 0.1778 0.5588)
			(layers "F.Cu" "F.Mask" "F.Paste")
			(net "SMB_CK440_CLK_SCL")
		)
		(pad "A11" smd rect
			(at -3.875024 1.75006 90)
			(size 0.1778 0.5588)
			(layers "F.Cu" "F.Mask" "F.Paste")
			(net "CLK_CK440_SMB_ADDR0")
		)
		(pad "A12" smd rect
			(at -3.875024 2.249932 90)
			(size 0.1778 0.5588)
			(layers "F.Cu" "F.Mask" "F.Paste")
			(net "P3V3_CLK_GEN_VDDXTAL_CK440")
		)
		(pad "A13" smd rect
			(at -3.875024 2.750058 90)
			(size 0.1778 0.5588)
			(layers "F.Cu" "F.Mask" "F.Paste")
			(net "XTAL_CK440_25M_XIN")
		)
		(pad "A14" smd rect
			(at -3.875024 3.24993 90)
			(size 0.1778 0.5588)
			(layers "F.Cu" "F.Mask" "F.Paste")
			(net "GND")
		)
		(pad "A15" smd rect
			(at -3.24993 3.875024)
			(size 0.1778 0.5588)
			(layers "F.Cu" "F.Mask" "F.Paste")
			(net "Net_4288")
		)
		(pad "A16" smd rect
			(at -2.750058 3.875024)
			(size 0.1778 0.5588)
			(layers "F.Cu" "F.Mask" "F.Paste")
			(net "FM_CLK_CK440_SS_EN")
		)
		(pad "A17" smd rect
			(at -2.249932 3.875024)
			(size 0.1778 0.5588)
			(layers "F.Cu" "F.Mask" "F.Paste")
			(net "FM_CLK_EN_R")
		)
		(pad "A18" smd rect
			(at -1.75006 3.875024)
			(size 0.1778 0.5588)
			(layers "F.Cu" "F.Mask" "F.Paste")
			(net "Net_4263")
		)
		(pad "A19" smd rect
			(at -1.249934 3.875024)
			(size 0.1778 0.5588)
			(layers "F.Cu" "F.Mask" "F.Paste")
			(net "Net_4262")
		)
		(pad "A20" smd rect
			(at -0.750062 3.875024)
			(size 0.1778 0.5588)
			(layers "F.Cu" "F.Mask" "F.Paste")
			(net "Net_4261")
		)
		(pad "A21" smd rect
			(at -0.249936 3.875024)
			(size 0.1778 0.5588)
			(layers "F.Cu" "F.Mask" "F.Paste")
			(net "Net_4260")
		)
		(pad "A22" smd rect
			(at 0.249936 3.875024)
			(size 0.1778 0.5588)
			(layers "F.Cu" "F.Mask" "F.Paste")
			(net "Net_4259")
		)
		(pad "A23" smd rect
			(at 0.750062 3.875024)
			(size 0.1778 0.5588)
			(layers "F.Cu" "F.Mask" "F.Paste")
			(net "Net_4258")
		)
		(pad "A24" smd rect
			(at 1.249934 3.875024)
			(size 0.1778 0.5588)
			(layers "F.Cu" "F.Mask" "F.Paste")
			(net "Net_4257")
		)
		(pad "A25" smd rect
			(at 1.75006 3.875024)
			(size 0.1778 0.5588)
			(layers "F.Cu" "F.Mask" "F.Paste")
			(net "Net_4256")
		)
		(pad "A26" smd rect
			(at 2.249932 3.875024)
			(size 0.1778 0.5588)
			(layers "F.Cu" "F.Mask" "F.Paste")
			(net "CLK_GEN_CK440_OE3_N")
		)
		(pad "A27" smd rect
			(at 2.750058 3.875024)
			(size 0.1778 0.5588)
			(layers "F.Cu" "F.Mask" "F.Paste")
			(net "CLK_100M_CK440Q_2_DB800ZL_DN")
		)
		(pad "A28" smd rect
			(at 3.24993 3.875024)
			(size 0.1778 0.5588)
			(layers "F.Cu" "F.Mask" "F.Paste")
			(net "CLK_100M_CK440Q_2_DB800ZL_DP")
		)
		(pad "A29" smd rect
			(at 3.875024 3.24993 270)
			(size 0.1778 0.5588)
			(layers "F.Cu" "F.Mask" "F.Paste")
			(net "CLK_BUFFER_9ZXL0851E_8_15_OE2_N")
		)
		(pad "A30" smd rect
			(at 3.875024 2.750058 270)
			(size 0.1778 0.5588)
			(layers "F.Cu" "F.Mask" "F.Paste")
			(net "CLK_BUFFER_9ZXL0851E_0_7_OE1_N")
		)
		(pad "A31" smd rect
			(at 3.875024 2.249932 270)
			(size 0.1778 0.5588)
			(layers "F.Cu" "F.Mask" "F.Paste")
			(net "CLK_100M_CK440Q_1_DB800ZL_DN")
		)
		(pad "A32" smd rect
			(at 3.875024 1.75006 270)
			(size 0.1778 0.5588)
			(layers "F.Cu" "F.Mask" "F.Paste")
			(net "CLK_100M_CK440Q_1_DB800ZL_DP")
		)
		(pad "A33" smd rect
			(at 3.875024 1.249934 270)
			(size 0.1778 0.5588)
			(layers "F.Cu" "F.Mask" "F.Paste")
			(net "CLK_100M_CK440Q_0_DB2000QL_DN")
		)
		(pad "A34" smd rect
			(at 3.875024 0.750062 270)
			(size 0.1778 0.5588)
			(layers "F.Cu" "F.Mask" "F.Paste")
			(net "CLK_100M_CK440Q_0_DB2000QL_DP")
		)
		(pad "A35" smd rect
			(at 3.875024 0.249936 270)
			(size 0.1778 0.5588)
			(layers "F.Cu" "F.Mask" "F.Paste")
			(net "Net_4287")
		)
		(pad "A36" smd rect
			(at 3.875024 -0.249936 270)
			(size 0.1778 0.5588)
			(layers "F.Cu" "F.Mask" "F.Paste")
			(net "Net_4286")
		)
		(pad "A37" smd rect
			(at 3.875024 -0.750062 270)
			(size 0.1778 0.5588)
			(layers "F.Cu" "F.Mask" "F.Paste")
			(net "Net_4285")
		)
		(pad "A38" smd rect
			(at 3.875024 -1.249934 270)
			(size 0.1778 0.5588)
			(layers "F.Cu" "F.Mask" "F.Paste")
			(net "Net_4284")
		)
		(pad "A39" smd rect
			(at 3.875024 -1.75006 270)
			(size 0.1778 0.5588)
			(layers "F.Cu" "F.Mask" "F.Paste")
			(net "Net_4283")
		)
		(pad "A40" smd rect
			(at 3.875024 -2.249932 270)
			(size 0.1778 0.5588)
			(layers "F.Cu" "F.Mask" "F.Paste")
			(net "Net_4282")
		)
		(pad "A41" smd rect
			(at 3.875024 -2.750058 270)
			(size 0.1778 0.5588)
			(layers "F.Cu" "F.Mask" "F.Paste")
			(net "Net_4281")
		)
		(pad "A42" smd rect
			(at 3.875024 -3.24993 270)
			(size 0.1778 0.5588)
			(layers "F.Cu" "F.Mask" "F.Paste")
			(net "Net_4280")
		)
		(pad "A43" smd rect
			(at 3.24993 -3.875024)
			(size 0.1778 0.5588)
			(layers "F.Cu" "F.Mask" "F.Paste")
			(net "Net_4279")
		)
		(pad "A44" smd rect
			(at 2.750058 -3.875024)
			(size 0.1778 0.5588)
			(layers "F.Cu" "F.Mask" "F.Paste")
			(net "Net_4278")
		)
		(pad "A45" smd rect
			(at 2.249932 -3.875024)
			(size 0.1778 0.5588)
			(layers "F.Cu" "F.Mask" "F.Paste")
			(net "Net_4277")
		)
		(pad "A46" smd rect
			(at 1.75006 -3.875024)
			(size 0.1778 0.5588)
			(layers "F.Cu" "F.Mask" "F.Paste")
			(net "Net_4276")
		)
		(pad "A47" smd rect
			(at 1.249934 -3.875024)
			(size 0.1778 0.5588)
			(layers "F.Cu" "F.Mask" "F.Paste")
			(net "Net_4275")
		)
		(pad "A48" smd rect
			(at 0.750062 -3.875024)
			(size 0.1778 0.5588)
			(layers "F.Cu" "F.Mask" "F.Paste")
			(net "Net_4274")
		)
		(pad "A49" smd rect
			(at 0.249936 -3.875024)
			(size 0.1778 0.5588)
			(layers "F.Cu" "F.Mask" "F.Paste")
			(net "Net_4273")
		)
		(pad "A50" smd rect
			(at -0.249936 -3.875024)
			(size 0.1778 0.5588)
			(layers "F.Cu" "F.Mask" "F.Paste")
			(net "Net_4272")
		)
		(pad "A51" smd rect
			(at -0.750062 -3.875024)
			(size 0.1778 0.5588)
			(layers "F.Cu" "F.Mask" "F.Paste")
			(net "Net_4271")
		)
		(pad "A52" smd rect
			(at -1.249934 -3.875024)
			(size 0.1778 0.5588)
			(layers "F.Cu" "F.Mask" "F.Paste")
			(net "Net_4270")
		)
		(pad "A53" smd rect
			(at -1.75006 -3.875024)
			(size 0.1778 0.5588)
			(layers "F.Cu" "F.Mask" "F.Paste")
			(net "TP_CK440_SBI_DATA_OUT")
		)
		(pad "A54" smd rect
			(at -2.249932 -3.875024)
			(size 0.1778 0.5588)
			(layers "F.Cu" "F.Mask" "F.Paste")
			(net "PD_CK440_SBI_CLK")
		)
		(pad "A55" smd rect
			(at -2.750058 -3.875024)
			(size 0.1778 0.5588)
			(layers "F.Cu" "F.Mask" "F.Paste")
			(net "Net_4269")
		)
		(pad "A56" smd rect
			(at -3.24993 -3.875024)
			(size 0.1778 0.5588)
			(layers "F.Cu" "F.Mask" "F.Paste")
			(net "Net_4268")
		)
		(pad "B1" smd rect
			(at -3.124962 -2.500122 90)
			(size 0.2794 0.4572)
			(layers "F.Cu" "F.Mask" "F.Paste")
			(net "P3V3_CLK_GEN_VDDA25M_CK440")
		)
		(pad "B2" smd rect
			(at -3.124962 -1.999996 90)
			(size 0.2794 0.4572)
			(layers "F.Cu" "F.Mask" "F.Paste")
			(net "Net_4292")
		)
		(pad "B3" smd rect
			(at -3.124962 -1.500124 90)
			(size 0.2794 0.4572)
			(layers "F.Cu" "F.Mask" "F.Paste")
			(net "Net_4299")
		)
		(pad "B4" smd rect
			(at -3.124962 -0.999998 90)
			(size 0.2794 0.4572)
			(layers "F.Cu" "F.Mask" "F.Paste")
			(net "PU_CLK_PFT_LOST_N")
		)
		(pad "B5" smd rect
			(at -3.124962 -0.499872 90)
			(size 0.2794 0.4572)
			(layers "F.Cu" "F.Mask" "F.Paste")
			(net "Net_4309")
		)
		(pad "B6" smd rect
			(at -3.124962 0 90)
			(size 0.2794 0.4572)
			(layers "F.Cu" "F.Mask" "F.Paste")
			(net "P3V3_CLK_GEN_VDDPT_CK440")
		)
		(pad "B7" smd rect
			(at -3.124962 0.499872 90)
			(size 0.2794 0.4572)
			(layers "F.Cu" "F.Mask" "F.Paste")
			(net "Net_4310")
		)
		(pad "B8" smd rect
			(at -3.124962 0.999998 90)
			(size 0.2794 0.4572)
			(layers "F.Cu" "F.Mask" "F.Paste")
			(net "SMB_CK440_CLK_SDA")
		)
		(pad "B9" smd rect
			(at -3.124962 1.500124 90)
			(size 0.2794 0.4572)
			(layers "F.Cu" "F.Mask" "F.Paste")
			(net "CLK_CK440_SMB_ADDR1")
		)
		(pad "B10" smd rect
			(at -3.124962 1.999996 90)
			(size 0.2794 0.4572)
			(layers "F.Cu" "F.Mask" "F.Paste")
			(net "GND")
		)
		(pad "B11" smd rect
			(at -3.124962 2.500122 90)
			(size 0.2794 0.4572)
			(layers "F.Cu" "F.Mask" "F.Paste")
			(net "XTAL_CK440_25M_XOUT")
		)
		(pad "B12" smd rect
			(at -2.500122 3.124962)
			(size 0.2794 0.4572)
			(layers "F.Cu" "F.Mask" "F.Paste")
			(net "GND")
		)
		(pad "B13" smd rect
			(at -1.999996 3.124962)
			(size 0.2794 0.4572)
			(layers "F.Cu" "F.Mask" "F.Paste")
			(net "Net_4289")
		)
		(pad "B14" smd rect
			(at -1.500124 3.124962)
			(size 0.2794 0.4572)
			(layers "F.Cu" "F.Mask" "F.Paste")
			(net "CLK_GEN_CK440_OE6_N")
		)
		(pad "B15" smd rect
			(at -0.999998 3.124962)
			(size 0.2794 0.4572)
			(layers "F.Cu" "F.Mask" "F.Paste")
			(net "CLK_GEN_CK440_OE5_N")
		)
		(pad "B16" smd rect
			(at -0.499872 3.124962)
			(size 0.2794 0.4572)
			(layers "F.Cu" "F.Mask" "F.Paste")
			(net "Net_4290")
		)
		(pad "B17" smd rect
			(at 0 3.124962)
			(size 0.2794 0.4572)
			(layers "F.Cu" "F.Mask" "F.Paste")
			(net "P3V3_CLK_GEN_VDDA100M_CK440")
		)
		(pad "B18" smd rect
			(at 0.499872 3.124962)
			(size 0.2794 0.4572)
			(layers "F.Cu" "F.Mask" "F.Paste")
			(net "Net_4291")
		)
		(pad "B19" smd rect
			(at 0.999998 3.124962)
			(size 0.2794 0.4572)
			(layers "F.Cu" "F.Mask" "F.Paste")
			(net "CLK_GEN_CK440_OE4_N")
		)
		(pad "B20" smd rect
			(at 1.500124 3.124962)
			(size 0.2794 0.4572)
			(layers "F.Cu" "F.Mask" "F.Paste")
			(net "Net_4293")
		)
		(pad "B21" smd rect
			(at 1.999996 3.124962)
			(size 0.2794 0.4572)
			(layers "F.Cu" "F.Mask" "F.Paste")
			(net "P3V3_CLK_GEN_VDD_CK440")
		)
		(pad "B22" smd rect
			(at 2.500122 3.124962)
			(size 0.2794 0.4572)
			(layers "F.Cu" "F.Mask" "F.Paste")
			(net "Net_4294")
		)
		(pad "B23" smd rect
			(at 3.124962 2.500122 270)
			(size 0.2794 0.4572)
			(layers "F.Cu" "F.Mask" "F.Paste")
			(net "P3V3_CLK_GEN_VDD_CK440")
		)
		(pad "B24" smd rect
			(at 3.124962 1.999996 270)
			(size 0.2794 0.4572)
			(layers "F.Cu" "F.Mask" "F.Paste")
			(net "Net_4295")
		)
		(pad "B25" smd rect
			(at 3.124962 1.500124 270)
			(size 0.2794 0.4572)
			(layers "F.Cu" "F.Mask" "F.Paste")
			(net "Net_4296")
		)
		(pad "B26" smd rect
			(at 3.124962 0.999998 270)
			(size 0.2794 0.4572)
			(layers "F.Cu" "F.Mask" "F.Paste")
			(net "Net_4297")
		)
		(pad "B27" smd rect
			(at 3.124962 0.499872 270)
			(size 0.2794 0.4572)
			(layers "F.Cu" "F.Mask" "F.Paste")
			(net "CLK_BUFFER_DB2000QL_OE0_N")
		)
		(pad "B28" smd rect
			(at 3.124962 0 270)
			(size 0.2794 0.4572)
			(layers "F.Cu" "F.Mask" "F.Paste")
			(net "Net_4298")
		)
		(pad "B29" smd rect
			(at 3.124962 -0.499872 270)
			(size 0.2794 0.4572)
			(layers "F.Cu" "F.Mask" "F.Paste")
			(net "P3V3_CLK_GEN_VDDMXCK_CK440")
		)
		(pad "B30" smd rect
			(at 3.124962 -0.999998 270)
			(size 0.2794 0.4572)
			(layers "F.Cu" "F.Mask" "F.Paste")
			(net "Net_4300")
		)
		(pad "B31" smd rect
			(at 3.124962 -1.500124 270)
			(size 0.2794 0.4572)
			(layers "F.Cu" "F.Mask" "F.Paste")
			(net "Net_4301")
		)
		(pad "B32" smd rect
			(at 3.124962 -1.999996 270)
			(size 0.2794 0.4572)
			(layers "F.Cu" "F.Mask" "F.Paste")
			(net "P3V3_CLK_GEN_VDDMXCK_CK440")
		)
		(pad "B33" smd rect
			(at 3.124962 -2.500122 270)
			(size 0.2794 0.4572)
			(layers "F.Cu" "F.Mask" "F.Paste")
			(net "Net_4302")
		)
		(pad "B34" smd rect
			(at 2.500122 -3.124962)
			(size 0.2794 0.4572)
			(layers "F.Cu" "F.Mask" "F.Paste")
			(net "Net_4303")
		)
		(pad "B35" smd rect
			(at 1.999996 -3.124962)
			(size 0.2794 0.4572)
			(layers "F.Cu" "F.Mask" "F.Paste")
			(net "P3V3_CLK_GEN_VDDMXCK_CK440")
		)
		(pad "B36" smd rect
			(at 1.500124 -3.124962)
			(size 0.2794 0.4572)
			(layers "F.Cu" "F.Mask" "F.Paste")
			(net "Net_4304")
		)
		(pad "B37" smd rect
			(at 0.999998 -3.124962)
			(size 0.2794 0.4572)
			(layers "F.Cu" "F.Mask" "F.Paste")
			(net "Net_4305")
		)
		(pad "B38" smd rect
			(at 0.499872 -3.124962)
			(size 0.2794 0.4572)
			(layers "F.Cu" "F.Mask" "F.Paste")
			(net "FM_CK440_MXCK_25M_100M")
		)
		(pad "B39" smd rect
			(at 0 -3.124962)
			(size 0.2794 0.4572)
			(layers "F.Cu" "F.Mask" "F.Paste")
			(net "Net_4306")
		)
		(pad "B40" smd rect
			(at -0.499872 -3.124962)
			(size 0.2794 0.4572)
			(layers "F.Cu" "F.Mask" "F.Paste")
			(net "P3V3_CLK_GEN_VDDMXCK_CK440")
		)
		(pad "B41" smd rect
			(at -0.999998 -3.124962)
			(size 0.2794 0.4572)
			(layers "F.Cu" "F.Mask" "F.Paste")
			(net "Net_4307")
		)
		(pad "B42" smd rect
			(at -1.500124 -3.124962)
			(size 0.2794 0.4572)
			(layers "F.Cu" "F.Mask" "F.Paste")
			(net "PU_CK440_SHFT_LD_N")
		)
		(pad "B43" smd rect
			(at -1.999996 -3.124962)
			(size 0.2794 0.4572)
			(layers "F.Cu" "F.Mask" "F.Paste")
			(net "PD_CK440_SBI_DATA_IN")
		)
		(pad "B44" smd rect
			(at -2.500122 -3.124962)
			(size 0.2794 0.4572)
			(layers "F.Cu" "F.Mask" "F.Paste")
			(net "Net_4308")
		)
		(pad "C1" smd circle
			(at 0 0)
			(size 0 0)
			(layers "F.Cu" "F.Mask" "F.Paste")
			(net "GND")
		)
	)
)
